(kicad_pcb
	(version 20241229)
	(generator "pcbnew")
	(generator_version "9.0")
	(general
		(thickness 1.6642)
		(legacy_teardrops no)
	)
	(paper "A3")
	(title_block
		(title "PolarFire SoM")
		(date "2025-07-22")
		(rev "1.1.4")
		(company "Antmicro Ltd")
		(comment 1 "www.antmicro.com")
		(comment 9 "footprints 213-216 of 470")
	)
	(layers
		(0 "F.Cu" mixed)
		(4 "In1.Cu" power)
		(6 "In2.Cu" signal)
		(8 "In3.Cu" power)
		(10 "In4.Cu" signal)
		(12 "In5.Cu" power)
		(14 "In6.Cu" power)
		(16 "In7.Cu" signal)
		(18 "In8.Cu" power)
		(20 "In9.Cu" signal)
		(22 "In10.Cu" power)
		(24 "In11.Cu" signal)
		(26 "In12.Cu" signal)
		(2 "B.Cu" mixed)
		(9 "F.Adhes" user "F.Adhesive")
		(11 "B.Adhes" user "B.Adhesive")
		(13 "F.Paste" user)
		(15 "B.Paste" user)
		(5 "F.SilkS" user "F.Silkscreen")
		(7 "B.SilkS" user "B.Silkscreen")
		(1 "F.Mask" user)
		(3 "B.Mask" user)
		(17 "Dwgs.User" user "User.Drawings")
		(19 "Cmts.User" user "User.Comments")
		(21 "Eco1.User" user "User.Eco1")
		(23 "Eco2.User" user "User.Eco2")
		(25 "Edge.Cuts" user)
		(27 "Margin" user)
		(31 "F.CrtYd" user "F.Courtyard")
		(29 "B.CrtYd" user "B.Courtyard")
		(35 "F.Fab" user)
		(33 "B.Fab" user)
	)
	(footprint "antmicro-footprints:C_0402_1005Metric"
		(layer "B.Cu")
		(at 208.11 144.54 180)
		(descr "Capacitor SMD 0402")
		(tags "capacitor SMD 0402")
		(property "Reference" "C202"
			(at 5.63 18.4 0)
			(layer "B.SilkS")
			(effects
				(font
					(size 0.7 0.7)
					(thickness 0.15)
				)
				(justify left bottom mirror)
			)
		)
		(property "Value" "C_10u_10V_0402"
			(at -1.022927 -2.155213 0)
			(layer "B.Fab")
			(hide yes)
			(effects
				(font
					(size 0.7 0.7)
					(thickness 0.15)
				)
				(justify left bottom mirror)
			)
		)
		(property "Datasheet" "https://www.murata.com/products/productdetail?partno=GRM155R61A106ME11%23"
			(at 0 0 180)
			(layer "F.Fab")
			(hide yes)
			(effects
				(font
					(size 1.27 1.27)
					(thickness 0.15)
				)
			)
		)
		(property "Description" "Multilayer Ceramic Capacitors MLCC - SMD/SMT 10 uF 10 VDC 20% 0402 X5R"
			(at 0 0 180)
			(layer "F.Fab")
			(hide yes)
			(effects
				(font
					(size 1.27 1.27)
					(thickness 0.15)
				)
			)
		)
		(property "Author" "Antmicro"
			(at 416.22 289.08 0)
			(layer "B.Fab")
			(hide yes)
			(effects
				(font
					(size 1 1)
					(thickness 0.15)
				)
				(justify mirror)
			)
		)
		(property "Dielectric" "X5R"
			(at 416.22 289.08 0)
			(layer "B.Fab")
			(hide yes)
			(effects
				(font
					(size 1 1)
					(thickness 0.15)
				)
				(justify mirror)
			)
		)
		(property "License" "Apache-2.0"
			(at 416.22 289.08 0)
			(layer "B.Fab")
			(hide yes)
			(effects
				(font
					(size 1 1)
					(thickness 0.15)
				)
				(justify mirror)
			)
		)
		(property "MPN" "GRM155R61A106ME11D"
			(at 416.22 289.08 0)
			(layer "B.Fab")
			(hide yes)
			(effects
				(font
					(size 1 1)
					(thickness 0.15)
				)
				(justify mirror)
			)
		)
		(property "Manufacturer" "Murata"
			(at 416.22 289.08 0)
			(layer "B.Fab")
			(hide yes)
			(effects
				(font
					(size 1 1)
					(thickness 0.15)
				)
				(justify mirror)
			)
		)
		(property "Public" ""
			(at 416.22 289.08 0)
			(layer "B.Fab")
			(hide yes)
			(effects
				(font
					(size 1 1)
					(thickness 0.15)
				)
				(justify mirror)
			)
		)
		(property "Val" "10u"
			(at 416.22 289.08 0)
			(layer "B.Fab")
			(hide yes)
			(effects
				(font
					(size 1 1)
					(thickness 0.15)
				)
				(justify mirror)
			)
		)
		(property "Voltage" "10V"
			(at 416.22 289.08 0)
			(layer "B.Fab")
			(hide yes)
			(effects
				(font
					(size 1 1)
					(thickness 0.15)
				)
				(justify mirror)
			)
		)
		(sheetname "/MIPI CrossLink/")
		(sheetfile "crosslink.kicad_sch")
		(attr smd)
		(fp_rect
			(start -0.925 0.47)
			(end 0.925 -0.47)
			(stroke
				(width 0.05)
				(type default)
			)
			(fill no)
			(layer "B.CrtYd")
		)
		(fp_line
			(start 0.504 0.25)
			(end 0.504 -0.248)
			(stroke
				(width 0.15)
				(type solid)
			)
			(layer "B.Fab")
		)
		(fp_line
			(start 0.504 -0.248)
			(end -0.494 -0.248)
			(stroke
				(width 0.15)
				(type solid)
			)
			(layer "B.Fab")
		)
		(fp_line
			(start -0.494 0.25)
			(end 0.504 0.25)
			(stroke
				(width 0.15)
				(type solid)
			)
			(layer "B.Fab")
		)
		(fp_line
			(start -0.494 -0.248)
			(end -0.494 0.25)
			(stroke
				(width 0.15)
				(type solid)
			)
			(layer "B.Fab")
		)
		(fp_text user "${REFERENCE}"
			(at -0.939 -4.599 0)
			(layer "B.Fab")
			(effects
				(font
					(size 0.7 0.7)
					(thickness 0.15)
				)
				(justify left bottom mirror)
			)
		)
		(fp_text user "Author: Antmicro"
			(at -0.939 -3.399 0)
			(layer "B.Fab")
			(effects
				(font
					(size 0.7 0.7)
					(thickness 0.15)
				)
				(justify left bottom mirror)
			)
		)
		(fp_text user "License: Apache-2.0"
			(at -0.939 -5.799 0)
			(layer "B.Fab")
			(effects
				(font
					(size 0.7 0.7)
					(thickness 0.15)
				)
				(justify left bottom mirror)
			)
		)
		(pad "1" smd roundrect
			(at -0.48 0 180)
			(size 0.59 0.64)
			(layers "B.Cu" "B.Mask" "B.Paste")
			(roundrect_rratio 0.25)
			(net 417 "GND")
			(pintype "passive")
		)
		(pad "2" smd roundrect
			(at 0.48 0 180)
			(size 0.59 0.64)
			(layers "B.Cu" "B.Mask" "B.Paste")
			(roundrect_rratio 0.25)
			(net 185 "/MIPI CrossLink/CL_VCCIO1")
			(pintype "passive")
		)
	)
	(footprint "antmicro-footprints:R_0402_1005Metric"
		(layer "B.Cu")
		(at 218.975 138.775 180)
		(descr "Resistor SMD 0402")
		(tags "resistor SMD 0402")
		(property "Reference" "R51"
			(at 0.75 -0.475 0)
			(layer "B.SilkS")
			(effects
				(font
					(size 0.7 0.7)
					(thickness 0.15)
				)
				(justify left bottom mirror)
			)
		)
		(property "Value" "R_10k_0402"
			(at -1.011843 -1.772047 0)
			(layer "B.Fab")
			(hide yes)
			(effects
				(font
					(size 0.7 0.7)
					(thickness 0.15)
				)
				(justify left bottom mirror)
			)
		)
		(property "Datasheet" "https://www.bourns.com/docs/product-datasheets/cr.pdf"
			(at 0 0 180)
			(layer "F.Fab")
			(hide yes)
			(effects
				(font
					(size 1.27 1.27)
					(thickness 0.15)
				)
			)
		)
		(property "Description" "SMD Chip Resistor, 10 kohm, ± 1%, 62.5 mW, 0402 [1005 Metric], Thick Film, General Purpose"
			(at 0 0 180)
			(layer "F.Fab")
			(hide yes)
			(effects
				(font
					(size 1.27 1.27)
					(thickness 0.15)
				)
			)
		)
		(property "Author" "Antmicro"
			(at 437.95 277.55 0)
			(layer "B.Fab")
			(hide yes)
			(effects
				(font
					(size 1 1)
					(thickness 0.15)
				)
				(justify mirror)
			)
		)
		(property "License" "Apache-2.0"
			(at 437.95 277.55 0)
			(layer "B.Fab")
			(hide yes)
			(effects
				(font
					(size 1 1)
					(thickness 0.15)
				)
				(justify mirror)
			)
		)
		(property "MPN" "CR0402-FX-1002GLF"
			(at 437.95 277.55 0)
			(layer "B.Fab")
			(hide yes)
			(effects
				(font
					(size 1 1)
					(thickness 0.15)
				)
				(justify mirror)
			)
		)
		(property "Manufacturer" "Bourns"
			(at 437.95 277.55 0)
			(layer "B.Fab")
			(hide yes)
			(effects
				(font
					(size 1 1)
					(thickness 0.15)
				)
				(justify mirror)
			)
		)
		(property "Public" ""
			(at 437.95 277.55 0)
			(layer "B.Fab")
			(hide yes)
			(effects
				(font
					(size 1 1)
					(thickness 0.15)
				)
				(justify mirror)
			)
		)
		(property "Tolerance" "1%"
			(at 437.95 277.55 0)
			(layer "B.Fab")
			(hide yes)
			(effects
				(font
					(size 1 1)
					(thickness 0.15)
				)
				(justify mirror)
			)
		)
		(property "Val" "10k"
			(at 437.95 277.55 0)
			(layer "B.Fab")
			(hide yes)
			(effects
				(font
					(size 1 1)
					(thickness 0.15)
				)
				(justify mirror)
			)
		)
		(sheetname "/Memory/")
		(sheetfile "memory.kicad_sch")
		(attr smd)
		(fp_rect
			(start -0.925 0.47)
			(end 0.925 -0.47)
			(stroke
				(width 0.05)
				(type default)
			)
			(fill no)
			(layer "B.CrtYd")
		)
		(fp_rect
			(start -0.5 0.25)
			(end 0.5 -0.25)
			(stroke
				(width 0.15)
				(type solid)
			)
			(fill no)
			(layer "B.Fab")
		)
		(fp_text user "${REFERENCE}"
			(at -0.95 -3.168 0)
			(layer "B.Fab")
			(effects
				(font
					(size 0.7 0.7)
					(thickness 0.15)
				)
				(justify left bottom mirror)
			)
		)
		(fp_text user "License: Apache-2.0"
			(at -0.95 -5.169 0)
			(layer "B.Fab")
			(effects
				(font
					(size 0.7 0.7)
					(thickness 0.15)
				)
				(justify left bottom mirror)
			)
		)
		(fp_text user "Author: Antmicro"
			(at -0.95 -4.169 0)
			(layer "B.Fab")
			(effects
				(font
					(size 0.7 0.7)
					(thickness 0.15)
				)
				(justify left bottom mirror)
			)
		)
		(pad "1" smd roundrect
			(at -0.48 0 180)
			(size 0.59 0.64)
			(layers "B.Cu" "B.Mask" "B.Paste")
			(roundrect_rratio 0.25)
			(net 517 "SD_VDD_FLAG")
			(pintype "passive")
		)
		(pad "2" smd roundrect
			(at 0.48 0 180)
			(size 0.59 0.64)
			(layers "B.Cu" "B.Mask" "B.Paste")
			(roundrect_rratio 0.25)
			(net 649 "VDD")
			(pintype "passive")
		)
	)
	(footprint "antmicro-footprints:C_0402_1005Metric"
		(layer "B.Cu")
		(at 180.05 134.45 -90)
		(descr "Capacitor SMD 0402")
		(tags "capacitor SMD 0402")
		(property "Reference" "C263"
			(at -1.975 -1.47 90)
			(layer "B.SilkS")
			(effects
				(font
					(size 0.7 0.7)
					(thickness 0.15)
				)
				(justify left bottom mirror)
			)
		)
		(property "Value" "C_10u_0402"
			(at -1.022927 -2.155213 90)
			(layer "B.Fab")
			(hide yes)
			(effects
				(font
					(size 0.7 0.7)
					(thickness 0.15)
				)
				(justify left bottom mirror)
			)
		)
		(property "Datasheet" "https://www.yageo.com/en/Chart/Download/pdf/CC0402MRX5R5BB106"
			(at 0 0 270)
			(layer "F.Fab")
			(hide yes)
			(effects
				(font
					(size 1.27 1.27)
					(thickness 0.15)
				)
			)
		)
		(property "Description" "SMD Multilayer Ceramic Capacitor, 10 µF, 6.3 V, 0402 [1005 Metric], ± 20%, X5R, CC Series"
			(at 0 0 270)
			(layer "F.Fab")
			(hide yes)
			(effects
				(font
					(size 1.27 1.27)
					(thickness 0.15)
				)
			)
		)
		(property "Author" "Antmicro"
			(at 45.6 314.5 0)
			(layer "B.Fab")
			(hide yes)
			(effects
				(font
					(size 1 1)
					(thickness 0.15)
				)
				(justify mirror)
			)
		)
		(property "Dielectric" ""
			(at 45.6 314.5 0)
			(layer "B.Fab")
			(hide yes)
			(effects
				(font
					(size 1 1)
					(thickness 0.15)
				)
				(justify mirror)
			)
		)
		(property "License" "Apache-2.0"
			(at 45.6 314.5 0)
			(layer "B.Fab")
			(hide yes)
			(effects
				(font
					(size 1 1)
					(thickness 0.15)
				)
				(justify mirror)
			)
		)
		(property "MPN" "CC0402MRX5R5BB106"
			(at 45.6 314.5 0)
			(layer "B.Fab")
			(hide yes)
			(effects
				(font
					(size 1 1)
					(thickness 0.15)
				)
				(justify mirror)
			)
		)
		(property "Manufacturer" "YAGEO"
			(at 45.6 314.5 0)
			(layer "B.Fab")
			(hide yes)
			(effects
				(font
					(size 1 1)
					(thickness 0.15)
				)
				(justify mirror)
			)
		)
		(property "Public" ""
			(at 45.6 314.5 0)
			(layer "B.Fab")
			(hide yes)
			(effects
				(font
					(size 1 1)
					(thickness 0.15)
				)
				(justify mirror)
			)
		)
		(property "Val" "10u"
			(at 45.6 314.5 0)
			(layer "B.Fab")
			(hide yes)
			(effects
				(font
					(size 1 1)
					(thickness 0.15)
				)
				(justify mirror)
			)
		)
		(property "Voltage" ""
			(at 45.6 314.5 0)
			(layer "B.Fab")
			(hide yes)
			(effects
				(font
					(size 1 1)
					(thickness 0.15)
				)
				(justify mirror)
			)
		)
		(sheetname "/LPDDR4/")
		(sheetfile "lpddr.kicad_sch")
		(attr smd)
		(fp_rect
			(start -0.925 0.47)
			(end 0.925 -0.47)
			(stroke
				(width 0.05)
				(type default)
			)
			(fill no)
			(layer "B.CrtYd")
		)
		(fp_line
			(start -0.494 0.25)
			(end 0.504 0.25)
			(stroke
				(width 0.15)
				(type solid)
			)
			(layer "B.Fab")
		)
		(fp_line
			(start 0.504 0.25)
			(end 0.504 -0.248)
			(stroke
				(width 0.15)
				(type solid)
			)
			(layer "B.Fab")
		)
		(fp_line
			(start -0.494 -0.248)
			(end -0.494 0.25)
			(stroke
				(width 0.15)
				(type solid)
			)
			(layer "B.Fab")
		)
		(fp_line
			(start 0.504 -0.248)
			(end -0.494 -0.248)
			(stroke
				(width 0.15)
				(type solid)
			)
			(layer "B.Fab")
		)
		(fp_text user "Author: Antmicro"
			(at -0.939 -3.399 90)
			(layer "B.Fab")
			(effects
				(font
					(size 0.7 0.7)
					(thickness 0.15)
				)
				(justify left bottom mirror)
			)
		)
		(fp_text user "License: Apache-2.0"
			(at -0.939 -5.799 90)
			(layer "B.Fab")
			(effects
				(font
					(size 0.7 0.7)
					(thickness 0.15)
				)
				(justify left bottom mirror)
			)
		)
		(fp_text user "${REFERENCE}"
			(at -0.939 -4.599 90)
			(layer "B.Fab")
			(effects
				(font
					(size 0.7 0.7)
					(thickness 0.15)
				)
				(justify left bottom mirror)
			)
		)
		(pad "1" smd roundrect
			(at -0.48 0 270)
			(size 0.59 0.64)
			(layers "B.Cu" "B.Mask" "B.Paste")
			(roundrect_rratio 0.25)
			(net 417 "GND")
			(pintype "passive")
		)
		(pad "2" smd roundrect
			(at 0.48 0 270)
			(size 0.59 0.64)
			(layers "B.Cu" "B.Mask" "B.Paste")
			(roundrect_rratio 0.25)
			(net 2 "+1V1")
			(pintype "passive")
		)
	)
	(footprint "antmicro-footprints:R_0402_1005Metric"
		(layer "B.Cu")
		(at 215.061 124.754 180)
		(descr "Resistor SMD 0402")
		(tags "resistor SMD 0402")
		(property "Reference" "R96"
			(at -2.964 -0.296 0)
			(layer "B.SilkS")
			(effects
				(font
					(size 0.7 0.7)
					(thickness 0.15)
				)
				(justify left bottom mirror)
			)
		)
		(property "Value" "R_2k2_0402"
			(at -1.011843 -1.772047 0)
			(layer "B.Fab")
			(hide yes)
			(effects
				(font
					(size 0.7 0.7)
					(thickness 0.15)
				)
				(justify left bottom mirror)
			)
		)
		(property "Datasheet" "https://www.bourns.com/docs/product-datasheets/cr.pdf"
			(at 0 0 180)
			(layer "F.Fab")
			(hide yes)
			(effects
				(font
					(size 1.27 1.27)
					(thickness 0.15)
				)
			)
		)
		(property "Description" "SMD Chip Resistor, 2.2 kohm, ± 1%, 62.5 mW, 0402 [1005 Metric], Thick Film, General Purpose"
			(at 0 0 180)
			(layer "F.Fab")
			(hide yes)
			(effects
				(font
					(size 1.27 1.27)
					(thickness 0.15)
				)
			)
		)
		(property "Author" "Antmicro"
			(at 430.122 249.508 0)
			(layer "B.Fab")
			(hide yes)
			(effects
				(font
					(size 1 1)
					(thickness 0.15)
				)
				(justify mirror)
			)
		)
		(property "License" "Apache-2.0"
			(at 430.122 249.508 0)
			(layer "B.Fab")
			(hide yes)
			(effects
				(font
					(size 1 1)
					(thickness 0.15)
				)
				(justify mirror)
			)
		)
		(property "MPN" "CR0402-FX-2201GLF"
			(at 430.122 249.508 0)
			(layer "B.Fab")
			(hide yes)
			(effects
				(font
					(size 1 1)
					(thickness 0.15)
				)
				(justify mirror)
			)
		)
		(property "Manufacturer" "Bourns"
			(at 430.122 249.508 0)
			(layer "B.Fab")
			(hide yes)
			(effects
				(font
					(size 1 1)
					(thickness 0.15)
				)
				(justify mirror)
			)
		)
		(property "Public" ""
			(at 430.122 249.508 0)
			(layer "B.Fab")
			(hide yes)
			(effects
				(font
					(size 1 1)
					(thickness 0.15)
				)
				(justify mirror)
			)
		)
		(property "Tolerance" "1%"
			(at 430.122 249.508 0)
			(layer "B.Fab")
			(hide yes)
			(effects
				(font
					(size 1 1)
					(thickness 0.15)
				)
				(justify mirror)
			)
		)
		(property "Val" "2k2"
			(at 430.122 249.508 0)
			(layer "B.Fab")
			(hide yes)
			(effects
				(font
					(size 1 1)
					(thickness 0.15)
				)
				(justify mirror)
			)
		)
		(sheetname "/Ethernet/")
		(sheetfile "ethernet.kicad_sch")
		(attr smd)
		(fp_rect
			(start -0.925 0.47)
			(end 0.925 -0.47)
			(stroke
				(width 0.05)
				(type default)
			)
			(fill no)
			(layer "B.CrtYd")
		)
		(fp_rect
			(start -0.5 0.25)
			(end 0.5 -0.25)
			(stroke
				(width 0.15)
				(type solid)
			)
			(fill no)
			(layer "B.Fab")
		)
		(fp_text user "Author: Antmicro"
			(at -0.95 -4.169 0)
			(layer "B.Fab")
			(effects
				(font
					(size 0.7 0.7)
					(thickness 0.15)
				)
				(justify left bottom mirror)
			)
		)
		(fp_text user "${REFERENCE}"
			(at -0.95 -3.168 0)
			(layer "B.Fab")
			(effects
				(font
					(size 0.7 0.7)
					(thickness 0.15)
				)
				(justify left bottom mirror)
			)
		)
		(fp_text user "License: Apache-2.0"
			(at -0.95 -5.169 0)
			(layer "B.Fab")
			(effects
				(font
					(size 0.7 0.7)
					(thickness 0.15)
				)
				(justify left bottom mirror)
			)
		)
		(pad "1" smd roundrect
			(at -0.48 0 180)
			(size 0.59 0.64)
			(layers "B.Cu" "B.Mask" "B.Paste")
			(roundrect_rratio 0.25)
			(net 417 "GND")
			(pintype "passive")
		)
		(pad "2" smd roundrect
			(at 0.48 0 180)
			(size 0.59 0.64)
			(layers "B.Cu" "B.Mask" "B.Paste")
			(roundrect_rratio 0.25)
			(net 282 "/Ethernet/ETH_RXCTRL")
			(pintype "passive")
		)
	)
)
